(kicad_pcb
	(version 20260206)
	(generator "pcbnew")
	(generator_version "10.0")
	(general
		(thickness 1.6)
		(legacy_teardrops no)
	)
	(paper "A4")
	(title_block
		(title "03242023_DA0F0TMBIJ0_F0T_Motherboard_J_brd_V01_OCP.brd")
		(comment 1 "Grand Teton / footprints 251-256 of 6105")
	)
	(layers
		(0 "F.Cu" signal "TOP")
		(4 "In1.Cu" signal "GND")
		(6 "In2.Cu" signal "IN1")
		(8 "In3.Cu" signal "GND1")
		(10 "In4.Cu" signal "IN2")
		(12 "In5.Cu" signal "GND2")
		(14 "In6.Cu" signal "IN3")
		(16 "In7.Cu" signal "GND3")
		(18 "In8.Cu" signal "VCC")
		(20 "In9.Cu" signal "VCC1")
		(22 "In10.Cu" signal "GND4")
		(24 "In11.Cu" signal "IN4")
		(26 "In12.Cu" signal "GND5")
		(28 "In13.Cu" signal "IN5")
		(30 "In14.Cu" signal "GND6")
		(32 "In15.Cu" signal "IN6")
		(34 "In16.Cu" signal "GND7")
		(2 "B.Cu" signal "BOTTOM")
		(9 "F.Adhes" user "F.Adhesive")
		(11 "B.Adhes" user "B.Adhesive")
		(13 "F.Paste" user "Package Geometry/Pastemask Top")
		(15 "B.Paste" user "Package Geometry/Pastemask Bottom")
		(5 "F.SilkS" user "Ref Des/Silkscreen Top")
		(7 "B.SilkS" user "Ref Des/Silkscreen Bottom")
		(1 "F.Mask" user "Board Geometry/Soldermask Top")
		(3 "B.Mask" user "Board Geometry/Soldermask Bottom")
		(17 "Dwgs.User" user "User.Drawings")
		(19 "Cmts.User" user "User.Comments")
		(21 "Eco1.User" user "User.Eco1")
		(23 "Eco2.User" user "User.Eco2")
		(25 "Edge.Cuts" user "Board Geometry/Outline")
		(27 "Margin" user)
		(31 "F.CrtYd" user "Package Geometry/Place Bound Top")
		(29 "B.CrtYd" user "Package Geometry/Place Bound Bottom")
		(35 "F.Fab" user "Ref Des/Assembly Top")
		(33 "B.Fab" user "Ref Des/Assembly Bottom")
	)
	(footprint ""
		(layer "F.Cu")
		(at 118.781576 -338.3026 -90)
		(property "Reference" "PC1358"
			(at 0 0 270)
			(layer "F.SilkS")
			(hide yes)
			(effects
				(font
					(size 1.27 1.27)
				)
			)
		)
		(property "Value" ""
			(at 0 0 270)
			(layer "F.Fab")
			(effects
				(font
					(size 1.27 1.27)
				)
			)
		)
		(duplicate_pad_numbers_are_jumpers no)
		(fp_line
			(start -0.7874 0.4064)
			(end -0.7874 -0.4064)
			(stroke
				(width 0.1524)
				(type default)
			)
			(layer "F.SilkS")
		)
		(fp_line
			(start 0.7874 0.4064)
			(end -0.7874 0.4064)
			(stroke
				(width 0.1524)
				(type default)
			)
			(layer "F.SilkS")
		)
		(fp_line
			(start -0.7874 -0.4064)
			(end 0.7874 -0.4064)
			(stroke
				(width 0.1524)
				(type default)
			)
			(layer "F.SilkS")
		)
		(fp_line
			(start 0.7874 -0.4064)
			(end 0.7874 0.4064)
			(stroke
				(width 0.1524)
				(type default)
			)
			(layer "F.SilkS")
		)
		(fp_line
			(start -0.67945 0.3048)
			(end -0.67945 -0.305054)
			(stroke
				(width 0.1)
				(type default)
			)
			(layer "F.Fab")
		)
		(fp_line
			(start -0.12065 0.3048)
			(end -0.67945 0.3048)
			(stroke
				(width 0.1)
				(type default)
			)
			(layer "F.Fab")
		)
		(fp_line
			(start 0.120396 0.3048)
			(end 0.120396 0.2794)
			(stroke
				(width 0.1)
				(type default)
			)
			(layer "F.Fab")
		)
		(fp_line
			(start 0.67945 0.3048)
			(end 0.120396 0.3048)
			(stroke
				(width 0.1)
				(type default)
			)
			(layer "F.Fab")
		)
		(fp_line
			(start -0.12065 0.2794)
			(end -0.12065 0.3048)
			(stroke
				(width 0.1)
				(type default)
			)
			(layer "F.Fab")
		)
		(fp_line
			(start 0.120396 0.2794)
			(end -0.12065 0.2794)
			(stroke
				(width 0.1)
				(type default)
			)
			(layer "F.Fab")
		)
		(fp_line
			(start -0.12065 -0.2794)
			(end 0.12065 -0.2794)
			(stroke
				(width 0.1)
				(type default)
			)
			(layer "F.Fab")
		)
		(fp_line
			(start 0.12065 -0.2794)
			(end 0.12065 -0.3048)
			(stroke
				(width 0.1)
				(type default)
			)
			(layer "F.Fab")
		)
		(fp_line
			(start 0.12065 -0.3048)
			(end 0.67945 -0.3048)
			(stroke
				(width 0.1)
				(type default)
			)
			(layer "F.Fab")
		)
		(fp_line
			(start 0.67945 -0.3048)
			(end 0.67945 0.3048)
			(stroke
				(width 0.1)
				(type default)
			)
			(layer "F.Fab")
		)
		(fp_line
			(start -0.67945 -0.305054)
			(end -0.12065 -0.305054)
			(stroke
				(width 0.1)
				(type default)
			)
			(layer "F.Fab")
		)
		(fp_line
			(start -0.12065 -0.305054)
			(end -0.12065 -0.2794)
			(stroke
				(width 0.1)
				(type default)
			)
			(layer "F.Fab")
		)
		(pad "1" smd circle
			(at -0.40005 0 270)
			(size 0 0)
			(layers "F.Cu" "F.Mask" "F.Paste")
			(net "GND")
		)
		(pad "2" smd circle
			(at 0.40005 0 270)
			(size 0 0)
			(layers "F.Cu" "F.Mask" "F.Paste")
			(net "PVCCIN_CPU1_VREF")
		)
	)
	(footprint ""
		(layer "F.Cu")
		(at 197.19036 -124.170948)
		(property "Reference" "R1710"
			(at 0 0 0)
			(layer "F.SilkS")
			(hide yes)
			(effects
				(font
					(size 1.27 1.27)
				)
			)
		)
		(property "Value" ""
			(at 0 0 0)
			(layer "F.Fab")
			(effects
				(font
					(size 1.27 1.27)
				)
			)
		)
		(duplicate_pad_numbers_are_jumpers no)
		(fp_line
			(start -0.7874 -0.4064)
			(end 0.7874 -0.4064)
			(stroke
				(width 0.1524)
				(type default)
			)
			(layer "F.SilkS")
		)
		(fp_line
			(start -0.7874 0.4064)
			(end -0.7874 -0.4064)
			(stroke
				(width 0.1524)
				(type default)
			)
			(layer "F.SilkS")
		)
		(fp_line
			(start 0.7874 -0.4064)
			(end 0.7874 0.4064)
			(stroke
				(width 0.1524)
				(type default)
			)
			(layer "F.SilkS")
		)
		(fp_line
			(start 0.7874 0.4064)
			(end -0.7874 0.4064)
			(stroke
				(width 0.1524)
				(type default)
			)
			(layer "F.SilkS")
		)
		(fp_line
			(start -0.67945 -0.305054)
			(end -0.12065 -0.305054)
			(stroke
				(width 0.1)
				(type default)
			)
			(layer "F.Fab")
		)
		(fp_line
			(start -0.67945 0.3048)
			(end -0.67945 -0.305054)
			(stroke
				(width 0.1)
				(type default)
			)
			(layer "F.Fab")
		)
		(fp_line
			(start -0.12065 -0.305054)
			(end -0.12065 -0.2794)
			(stroke
				(width 0.1)
				(type default)
			)
			(layer "F.Fab")
		)
		(fp_line
			(start -0.12065 -0.2794)
			(end 0.12065 -0.2794)
			(stroke
				(width 0.1)
				(type default)
			)
			(layer "F.Fab")
		)
		(fp_line
			(start -0.12065 0.2794)
			(end -0.12065 0.3048)
			(stroke
				(width 0.1)
				(type default)
			)
			(layer "F.Fab")
		)
		(fp_line
			(start -0.12065 0.3048)
			(end -0.67945 0.3048)
			(stroke
				(width 0.1)
				(type default)
			)
			(layer "F.Fab")
		)
		(fp_line
			(start 0.120396 0.2794)
			(end -0.12065 0.2794)
			(stroke
				(width 0.1)
				(type default)
			)
			(layer "F.Fab")
		)
		(fp_line
			(start 0.120396 0.3048)
			(end 0.120396 0.2794)
			(stroke
				(width 0.1)
				(type default)
			)
			(layer "F.Fab")
		)
		(fp_line
			(start 0.12065 -0.3048)
			(end 0.67945 -0.3048)
			(stroke
				(width 0.1)
				(type default)
			)
			(layer "F.Fab")
		)
		(fp_line
			(start 0.12065 -0.2794)
			(end 0.12065 -0.3048)
			(stroke
				(width 0.1)
				(type default)
			)
			(layer "F.Fab")
		)
		(fp_line
			(start 0.67945 -0.3048)
			(end 0.67945 0.3048)
			(stroke
				(width 0.1)
				(type default)
			)
			(layer "F.Fab")
		)
		(fp_line
			(start 0.67945 0.3048)
			(end 0.120396 0.3048)
			(stroke
				(width 0.1)
				(type default)
			)
			(layer "F.Fab")
		)
		(pad "1" smd circle
			(at -0.40005 0)
			(size 0 0)
			(layers "F.Cu" "F.Mask" "F.Paste")
			(net "FM_PLD_REV_N")
		)
		(pad "2" smd circle
			(at 0.40005 0)
			(size 0 0)
			(layers "F.Cu" "F.Mask" "F.Paste")
			(net "FM_PLD_REV_R_N")
		)
	)
	(footprint ""
		(layer "F.Cu")
		(at 261.600188 -92.498926 90)
		(property "Reference" "R3638"
			(at 0 0 90)
			(layer "F.SilkS")
			(hide yes)
			(effects
				(font
					(size 1.27 1.27)
				)
			)
		)
		(property "Value" ""
			(at 0 0 90)
			(layer "F.Fab")
			(effects
				(font
					(size 1.27 1.27)
				)
			)
		)
		(duplicate_pad_numbers_are_jumpers no)
		(fp_line
			(start 0.7874 -0.4064)
			(end 0.7874 0.4064)
			(stroke
				(width 0.1524)
				(type default)
			)
			(layer "F.SilkS")
		)
		(fp_line
			(start -0.7874 -0.4064)
			(end 0.7874 -0.4064)
			(stroke
				(width 0.1524)
				(type default)
			)
			(layer "F.SilkS")
		)
		(fp_line
			(start 0.7874 0.4064)
			(end -0.7874 0.4064)
			(stroke
				(width 0.1524)
				(type default)
			)
			(layer "F.SilkS")
		)
		(fp_line
			(start -0.7874 0.4064)
			(end -0.7874 -0.4064)
			(stroke
				(width 0.1524)
				(type default)
			)
			(layer "F.SilkS")
		)
		(fp_line
			(start -0.12065 -0.305054)
			(end -0.12065 -0.2794)
			(stroke
				(width 0.1)
				(type default)
			)
			(layer "F.Fab")
		)
		(fp_line
			(start -0.67945 -0.305054)
			(end -0.12065 -0.305054)
			(stroke
				(width 0.1)
				(type default)
			)
			(layer "F.Fab")
		)
		(fp_line
			(start 0.67945 -0.3048)
			(end 0.67945 0.3048)
			(stroke
				(width 0.1)
				(type default)
			)
			(layer "F.Fab")
		)
		(fp_line
			(start 0.12065 -0.3048)
			(end 0.67945 -0.3048)
			(stroke
				(width 0.1)
				(type default)
			)
			(layer "F.Fab")
		)
		(fp_line
			(start 0.12065 -0.2794)
			(end 0.12065 -0.3048)
			(stroke
				(width 0.1)
				(type default)
			)
			(layer "F.Fab")
		)
		(fp_line
			(start -0.12065 -0.2794)
			(end 0.12065 -0.2794)
			(stroke
				(width 0.1)
				(type default)
			)
			(layer "F.Fab")
		)
		(fp_line
			(start 0.120396 0.2794)
			(end -0.12065 0.2794)
			(stroke
				(width 0.1)
				(type default)
			)
			(layer "F.Fab")
		)
		(fp_line
			(start -0.12065 0.2794)
			(end -0.12065 0.3048)
			(stroke
				(width 0.1)
				(type default)
			)
			(layer "F.Fab")
		)
		(fp_line
			(start 0.67945 0.3048)
			(end 0.120396 0.3048)
			(stroke
				(width 0.1)
				(type default)
			)
			(layer "F.Fab")
		)
		(fp_line
			(start 0.120396 0.3048)
			(end 0.120396 0.2794)
			(stroke
				(width 0.1)
				(type default)
			)
			(layer "F.Fab")
		)
		(fp_line
			(start -0.12065 0.3048)
			(end -0.67945 0.3048)
			(stroke
				(width 0.1)
				(type default)
			)
			(layer "F.Fab")
		)
		(fp_line
			(start -0.67945 0.3048)
			(end -0.67945 -0.305054)
			(stroke
				(width 0.1)
				(type default)
			)
			(layer "F.Fab")
		)
		(pad "1" smd circle
			(at -0.40005 0 90)
			(size 0 0)
			(layers "F.Cu" "F.Mask" "F.Paste")
			(net "P3V3_AUX")
		)
		(pad "2" smd circle
			(at 0.40005 0 90)
			(size 0 0)
			(layers "F.Cu" "F.Mask" "F.Paste")
			(net "CK440Q_OE_1")
		)
	)
	(footprint ""
		(layer "F.Cu")
		(at 435.185566 -40.104568 180)
		(property "Reference" "R1324"
			(at 0 0 180)
			(layer "F.SilkS")
			(hide yes)
			(effects
				(font
					(size 1.27 1.27)
				)
			)
		)
		(property "Value" ""
			(at 0 0 180)
			(layer "F.Fab")
			(effects
				(font
					(size 1.27 1.27)
				)
			)
		)
		(duplicate_pad_numbers_are_jumpers no)
		(fp_line
			(start 0.7874 0.4064)
			(end -0.7874 0.4064)
			(stroke
				(width 0.1524)
				(type default)
			)
			(layer "F.SilkS")
		)
		(fp_line
			(start 0.7874 -0.4064)
			(end 0.7874 0.4064)
			(stroke
				(width 0.1524)
				(type default)
			)
			(layer "F.SilkS")
		)
		(fp_line
			(start -0.7874 0.4064)
			(end -0.7874 -0.4064)
			(stroke
				(width 0.1524)
				(type default)
			)
			(layer "F.SilkS")
		)
		(fp_line
			(start -0.7874 -0.4064)
			(end 0.7874 -0.4064)
			(stroke
				(width 0.1524)
				(type default)
			)
			(layer "F.SilkS")
		)
		(fp_line
			(start 0.67945 0.3048)
			(end 0.120396 0.3048)
			(stroke
				(width 0.1)
				(type default)
			)
			(layer "F.Fab")
		)
		(fp_line
			(start 0.67945 -0.3048)
			(end 0.67945 0.3048)
			(stroke
				(width 0.1)
				(type default)
			)
			(layer "F.Fab")
		)
		(fp_line
			(start 0.12065 -0.2794)
			(end 0.12065 -0.3048)
			(stroke
				(width 0.1)
				(type default)
			)
			(layer "F.Fab")
		)
		(fp_line
			(start 0.12065 -0.3048)
			(end 0.67945 -0.3048)
			(stroke
				(width 0.1)
				(type default)
			)
			(layer "F.Fab")
		)
		(fp_line
			(start 0.120396 0.3048)
			(end 0.120396 0.2794)
			(stroke
				(width 0.1)
				(type default)
			)
			(layer "F.Fab")
		)
		(fp_line
			(start 0.120396 0.2794)
			(end -0.12065 0.2794)
			(stroke
				(width 0.1)
				(type default)
			)
			(layer "F.Fab")
		)
		(fp_line
			(start -0.12065 0.3048)
			(end -0.67945 0.3048)
			(stroke
				(width 0.1)
				(type default)
			)
			(layer "F.Fab")
		)
		(fp_line
			(start -0.12065 0.2794)
			(end -0.12065 0.3048)
			(stroke
				(width 0.1)
				(type default)
			)
			(layer "F.Fab")
		)
		(fp_line
			(start -0.12065 -0.2794)
			(end 0.12065 -0.2794)
			(stroke
				(width 0.1)
				(type default)
			)
			(layer "F.Fab")
		)
		(fp_line
			(start -0.12065 -0.305054)
			(end -0.12065 -0.2794)
			(stroke
				(width 0.1)
				(type default)
			)
			(layer "F.Fab")
		)
		(fp_line
			(start -0.67945 0.3048)
			(end -0.67945 -0.305054)
			(stroke
				(width 0.1)
				(type default)
			)
			(layer "F.Fab")
		)
		(fp_line
			(start -0.67945 -0.305054)
			(end -0.12065 -0.305054)
			(stroke
				(width 0.1)
				(type default)
			)
			(layer "F.Fab")
		)
		(pad "1" smd circle
			(at -0.40005 0 180)
			(size 0 0)
			(layers "F.Cu" "F.Mask" "F.Paste")
			(net "GND")
		)
		(pad "2" smd circle
			(at 0.40005 0 180)
			(size 0 0)
			(layers "F.Cu" "F.Mask" "F.Paste")
			(net "PD_BIOS_IMAGE_SWAP_N")
		)
	)
	(footprint ""
		(layer "F.Cu")
		(at 140.208 -370.423948 90)
		(property "Reference" "R2371"
			(at 0 0 90)
			(layer "F.SilkS")
			(hide yes)
			(effects
				(font
					(size 1.27 1.27)
				)
			)
		)
		(property "Value" ""
			(at 0 0 90)
			(layer "F.Fab")
			(effects
				(font
					(size 1.27 1.27)
				)
			)
		)
		(duplicate_pad_numbers_are_jumpers no)
		(fp_line
			(start 0.7874 -0.4064)
			(end 0.7874 0.4064)
			(stroke
				(width 0.1524)
				(type default)
			)
			(layer "F.SilkS")
		)
		(fp_line
			(start -0.7874 -0.4064)
			(end 0.7874 -0.4064)
			(stroke
				(width 0.1524)
				(type default)
			)
			(layer "F.SilkS")
		)
		(fp_line
			(start 0.7874 0.4064)
			(end -0.7874 0.4064)
			(stroke
				(width 0.1524)
				(type default)
			)
			(layer "F.SilkS")
		)
		(fp_line
			(start -0.7874 0.4064)
			(end -0.7874 -0.4064)
			(stroke
				(width 0.1524)
				(type default)
			)
			(layer "F.SilkS")
		)
		(fp_line
			(start -0.12065 -0.305054)
			(end -0.12065 -0.2794)
			(stroke
				(width 0.1)
				(type default)
			)
			(layer "F.Fab")
		)
		(fp_line
			(start -0.67945 -0.305054)
			(end -0.12065 -0.305054)
			(stroke
				(width 0.1)
				(type default)
			)
			(layer "F.Fab")
		)
		(fp_line
			(start 0.67945 -0.3048)
			(end 0.67945 0.3048)
			(stroke
				(width 0.1)
				(type default)
			)
			(layer "F.Fab")
		)
		(fp_line
			(start 0.12065 -0.3048)
			(end 0.67945 -0.3048)
			(stroke
				(width 0.1)
				(type default)
			)
			(layer "F.Fab")
		)
		(fp_line
			(start 0.12065 -0.2794)
			(end 0.12065 -0.3048)
			(stroke
				(width 0.1)
				(type default)
			)
			(layer "F.Fab")
		)
		(fp_line
			(start -0.12065 -0.2794)
			(end 0.12065 -0.2794)
			(stroke
				(width 0.1)
				(type default)
			)
			(layer "F.Fab")
		)
		(fp_line
			(start 0.120396 0.2794)
			(end -0.12065 0.2794)
			(stroke
				(width 0.1)
				(type default)
			)
			(layer "F.Fab")
		)
		(fp_line
			(start -0.12065 0.2794)
			(end -0.12065 0.3048)
			(stroke
				(width 0.1)
				(type default)
			)
			(layer "F.Fab")
		)
		(fp_line
			(start 0.67945 0.3048)
			(end 0.120396 0.3048)
			(stroke
				(width 0.1)
				(type default)
			)
			(layer "F.Fab")
		)
		(fp_line
			(start 0.120396 0.3048)
			(end 0.120396 0.2794)
			(stroke
				(width 0.1)
				(type default)
			)
			(layer "F.Fab")
		)
		(fp_line
			(start -0.12065 0.3048)
			(end -0.67945 0.3048)
			(stroke
				(width 0.1)
				(type default)
			)
			(layer "F.Fab")
		)
		(fp_line
			(start -0.67945 0.3048)
			(end -0.67945 -0.305054)
			(stroke
				(width 0.1)
				(type default)
			)
			(layer "F.Fab")
		)
		(pad "1" smd circle
			(at -0.40005 0 90)
			(size 0 0)
			(layers "F.Cu" "F.Mask" "F.Paste")
			(net "SMB_VR_3V3AUX_SCL_R3")
		)
		(pad "2" smd circle
			(at 0.40005 0 90)
			(size 0 0)
			(layers "F.Cu" "F.Mask" "F.Paste")
			(net "SMB_CLK_PVCCIN_CPU0")
		)
	)
	(footprint ""
		(layer "F.Cu")
		(at 446.727834 -179.862734)
		(property "Reference" "PC1279"
			(at 0 0 0)
			(layer "F.SilkS")
			(hide yes)
			(effects
				(font
					(size 1.27 1.27)
				)
			)
		)
		(property "Value" ""
			(at 0 0 0)
			(layer "F.Fab")
			(effects
				(font
					(size 1.27 1.27)
				)
			)
		)
		(duplicate_pad_numbers_are_jumpers no)
		(fp_line
			(start -1.524 -0.762)
			(end 1.524 -0.762)
			(stroke
				(width 0.1524)
				(type default)
			)
			(layer "F.SilkS")
		)
		(fp_line
			(start -1.524 0.762)
			(end -1.524 -0.762)
			(stroke
				(width 0.1524)
				(type default)
			)
			(layer "F.SilkS")
		)
		(fp_line
			(start 1.524 -0.762)
			(end 1.524 0.762)
			(stroke
				(width 0.1524)
				(type default)
			)
			(layer "F.SilkS")
		)
		(fp_line
			(start 1.524 0.762)
			(end -1.524 0.762)
			(stroke
				(width 0.1524)
				(type default)
			)
			(layer "F.SilkS")
		)
		(fp_line
			(start -1.1049 -0.724916)
			(end -1.1049 0.724916)
			(stroke
				(width 0.1)
				(type default)
			)
			(layer "F.Fab")
		)
		(fp_line
			(start -1.1049 0.724916)
			(end 1.1049 0.724916)
			(stroke
				(width 0.1)
				(type default)
			)
			(layer "F.Fab")
		)
		(fp_line
			(start 1.1049 -0.724916)
			(end -1.1049 -0.724916)
			(stroke
				(width 0.1)
				(type default)
			)
			(layer "F.Fab")
		)
		(fp_line
			(start 1.1049 0.724916)
			(end 1.1049 -0.724916)
			(stroke
				(width 0.1)
				(type default)
			)
			(layer "F.Fab")
		)
		(pad "1" smd rect
			(at -0.889 0 180)
			(size 1.016 1.27)
			(layers "F.Cu" "F.Mask" "F.Paste")
			(net "PVNN_MAIN_CPU0")
		)
		(pad "2" smd rect
			(at 0.889 0 180)
			(size 1.016 1.27)
			(layers "F.Cu" "F.Mask" "F.Paste")
			(net "GND")
		)
	)
)
